(kicad_sch
	(version 20250114)
	(generator "eeschema")
	(generator_version "9.0")
	(paper "A3")
	(title_block
		(title "SO-DIMM DDR5 Tester")
		(date "2025-11-26")
		(rev "1.3.0")
		(company "Antmicro Ltd.")
		(comment 1 "www.antmicro.com")
		(comment 2 "Antmicro Ltd")
	)
	(text "ETH_SEL"
		(exclude_from_sim no)
		(at 182.245 97.79 0)
		(effects
			(font
				(size 1.27 1.27)
			)
			(justify left bottom)
		)
	)
	(text "BANK 12"
		(exclude_from_sim no)
		(at 15.24 19.685 0)
		(effects
			(font
				(size 2.54 2.54)
				(thickness 0.5994)
				(bold yes)
			)
			(justify left bottom)
		)
	)
	(text "VCCO (HR banks) max: 3.6V"
		(exclude_from_sim no)
		(at 158.115 83.82 0)
		(effects
			(font
				(size 1.27 1.27)
			)
			(justify left bottom)
		)
	)
	(no_connect
		(at 191.77 88.9)
	)
	(no_connect
		(at 191.77 93.98)
	)
	(no_connect
		(at 191.77 124.46)
	)
	(no_connect
		(at 191.77 104.14)
	)
	(no_connect
		(at 191.77 162.56)
	)
	(no_connect
		(at 191.77 144.78)
	)
	(no_connect
		(at 191.77 101.6)
	)
	(no_connect
		(at 191.77 96.52)
	)
	(no_connect
		(at 191.77 116.84)
	)
	(no_connect
		(at 191.77 157.48)
	)
	(no_connect
		(at 191.77 119.38)
	)
	(no_connect
		(at 191.77 127)
	)
	(no_connect
		(at 191.77 91.44)
	)
	(bus_entry
		(at 138.43 153.67)
		(size 1.27 1.27)
		(stroke
			(width 0)
			(type default)
		)
	)
	(bus_entry
		(at 116.205 133.35)
		(size 1.27 1.27)
		(stroke
			(width 0)
			(type default)
		)
	)
	(bus_entry
		(at 138.43 151.13)
		(size 1.27 1.27)
		(stroke
			(width 0)
			(type default)
		)
	)
	(bus_entry
		(at 116.205 166.37)
		(size 1.27 1.27)
		(stroke
			(width 0)
			(type default)
		)
	)
	(bus_entry
		(at 138.43 212.09)
		(size 1.27 1.27)
		(stroke
			(width 0)
			(type default)
		)
	)
	(bus_entry
		(at 116.205 158.75)
		(size 1.27 1.27)
		(stroke
			(width 0)
			(type default)
		)
	)
	(bus_entry
		(at 138.43 128.27)
		(size 1.27 1.27)
		(stroke
			(width 0)
			(type default)
		)
	)
	(bus_entry
		(at 138.43 105.41)
		(size 1.27 1.27)
		(stroke
			(width 0)
			(type default)
		)
	)
	(bus_entry
		(at 138.43 146.05)
		(size 1.27 1.27)
		(stroke
			(width 0)
			(type default)
		)
	)
	(bus_entry
		(at 138.43 148.59)
		(size 1.27 1.27)
		(stroke
			(width 0)
			(type default)
		)
	)
	(bus_entry
		(at 116.205 204.47)
		(size 1.27 1.27)
		(stroke
			(width 0)
			(type default)
		)
	)
	(bus_entry
		(at 138.43 140.97)
		(size 1.27 1.27)
		(stroke
			(width 0)
			(type default)
		)
	)
	(bus_entry
		(at 116.205 191.77)
		(size 1.27 1.27)
		(stroke
			(width 0)
			(type default)
		)
	)
	(bus_entry
		(at 116.205 189.23)
		(size 1.27 1.27)
		(stroke
			(width 0)
			(type default)
		)
	)
	(bus_entry
		(at 138.43 120.65)
		(size 1.27 1.27)
		(stroke
			(width 0)
			(type default)
		)
	)
	(bus_entry
		(at 138.43 97.79)
		(size 1.27 1.27)
		(stroke
			(width 0)
			(type default)
		)
	)
	(bus_entry
		(at 138.43 107.95)
		(size 1.27 1.27)
		(stroke
			(width 0)
			(type default)
		)
	)
	(bus_entry
		(at 138.43 163.83)
		(size 1.27 1.27)
		(stroke
			(width 0)
			(type default)
		)
	)
	(bus_entry
		(at 116.205 207.01)
		(size 1.27 1.27)
		(stroke
			(width 0)
			(type default)
		)
	)
	(bus_entry
		(at 158.115 181.61)
		(size 1.27 1.27)
		(stroke
			(width 0)
			(type default)
		)
	)
	(bus_entry
		(at 138.43 130.81)
		(size 1.27 1.27)
		(stroke
			(width 0)
			(type default)
		)
	)
	(bus_entry
		(at 116.205 168.91)
		(size 1.27 1.27)
		(stroke
			(width 0)
			(type default)
		)
	)
	(bus_entry
		(at 138.43 135.89)
		(size 1.27 1.27)
		(stroke
			(width 0)
			(type default)
		)
	)
	(bus_entry
		(at 116.205 196.85)
		(size 1.27 1.27)
		(stroke
			(width 0)
			(type default)
		)
	)
	(bus_entry
		(at 158.115 179.07)
		(size 1.27 1.27)
		(stroke
			(width 0)
			(type default)
		)
	)
	(bus_entry
		(at 116.205 186.69)
		(size 1.27 1.27)
		(stroke
			(width 0)
			(type default)
		)
	)
	(bus_entry
		(at 116.205 194.31)
		(size 1.27 1.27)
		(stroke
			(width 0)
			(type default)
		)
	)
	(bus_entry
		(at 116.205 201.93)
		(size 1.27 1.27)
		(stroke
			(width 0)
			(type default)
		)
	)
	(bus_entry
		(at 138.43 138.43)
		(size 1.27 1.27)
		(stroke
			(width 0)
			(type default)
		)
	)
	(bus_entry
		(at 138.43 110.49)
		(size 1.27 1.27)
		(stroke
			(width 0)
			(type default)
		)
	)
	(bus_entry
		(at 116.205 199.39)
		(size 1.27 1.27)
		(stroke
			(width 0)
			(type default)
		)
	)
	(bus_entry
		(at 138.43 113.03)
		(size 1.27 1.27)
		(stroke
			(width 0)
			(type default)
		)
	)
	(bus
		(pts
			(xy 116.205 201.93) (xy 116.205 204.47)
		)
		(stroke
			(width 0)
			(type default)
		)
	)
	(wire
		(pts
			(xy 139.7 114.3) (xy 191.77 114.3)
		)
		(stroke
			(width 0)
			(type default)
		)
	)
	(wire
		(pts
			(xy 189.865 172.72) (xy 191.77 172.72)
		)
		(stroke
			(width 0)
			(type default)
		)
	)
	(wire
		(pts
			(xy 139.7 129.54) (xy 191.77 129.54)
		)
		(stroke
			(width 0)
			(type default)
		)
	)
	(wire
		(pts
			(xy 139.7 132.08) (xy 191.77 132.08)
		)
		(stroke
			(width 0)
			(type default)
		)
	)
	(bus
		(pts
			(xy 157.48 176.53) (xy 158.115 177.165)
		)
		(stroke
			(width 0)
			(type default)
		)
	)
	(wire
		(pts
			(xy 189.865 185.42) (xy 191.77 185.42)
		)
		(stroke
			(width 0)
			(type default)
		)
	)
	(bus
		(pts
			(xy 138.43 151.13) (xy 138.43 153.67)
		)
		(stroke
			(width 0)
			(type default)
		)
	)
	(wire
		(pts
			(xy 117.475 190.5) (xy 191.77 190.5)
		)
		(stroke
			(width 0)
			(type default)
		)
	)
	(bus
		(pts
			(xy 138.43 97.79) (xy 138.43 105.41)
		)
		(stroke
			(width 0)
			(type default)
		)
	)
	(bus
		(pts
			(xy 138.43 113.03) (xy 138.43 120.65)
		)
		(stroke
			(width 0)
			(type default)
		)
	)
	(bus
		(pts
			(xy 116.205 186.69) (xy 116.205 189.23)
		)
		(stroke
			(width 0)
			(type default)
		)
	)
	(bus
		(pts
			(xy 116.205 132.08) (xy 116.205 133.35)
		)
		(stroke
			(width 0)
			(type default)
		)
	)
	(wire
		(pts
			(xy 139.7 154.94) (xy 191.77 154.94)
		)
		(stroke
			(width 0)
			(type default)
		)
	)
	(wire
		(pts
			(xy 117.475 203.2) (xy 191.77 203.2)
		)
		(stroke
			(width 0)
			(type default)
		)
	)
	(bus
		(pts
			(xy 137.795 95.885) (xy 138.43 96.52)
		)
		(stroke
			(width 0)
			(type default)
		)
	)
	(wire
		(pts
			(xy 189.865 81.915) (xy 189.865 83.82)
		)
		(stroke
			(width 0)
			(type default)
		)
	)
	(wire
		(pts
			(xy 139.7 147.32) (xy 191.77 147.32)
		)
		(stroke
			(width 0)
			(type default)
		)
	)
	(bus
		(pts
			(xy 138.43 110.49) (xy 138.43 113.03)
		)
		(stroke
			(width 0)
			(type default)
		)
	)
	(bus
		(pts
			(xy 138.43 96.52) (xy 138.43 97.79)
		)
		(stroke
			(width 0)
			(type default)
		)
	)
	(bus
		(pts
			(xy 138.43 148.59) (xy 138.43 151.13)
		)
		(stroke
			(width 0)
			(type default)
		)
	)
	(wire
		(pts
			(xy 117.475 198.12) (xy 191.77 198.12)
		)
		(stroke
			(width 0)
			(type default)
		)
	)
	(bus
		(pts
			(xy 116.205 166.37) (xy 116.205 168.91)
		)
		(stroke
			(width 0)
			(type default)
		)
	)
	(bus
		(pts
			(xy 116.205 204.47) (xy 116.205 207.01)
		)
		(stroke
			(width 0)
			(type default)
		)
	)
	(wire
		(pts
			(xy 139.7 137.16) (xy 191.77 137.16)
		)
		(stroke
			(width 0)
			(type default)
		)
	)
	(wire
		(pts
			(xy 139.7 121.92) (xy 191.77 121.92)
		)
		(stroke
			(width 0)
			(type default)
		)
	)
	(wire
		(pts
			(xy 139.7 152.4) (xy 191.77 152.4)
		)
		(stroke
			(width 0)
			(type default)
		)
	)
	(bus
		(pts
			(xy 158.115 177.165) (xy 158.115 179.07)
		)
		(stroke
			(width 0)
			(type default)
		)
	)
	(bus
		(pts
			(xy 138.43 105.41) (xy 138.43 107.95)
		)
		(stroke
			(width 0)
			(type default)
		)
	)
	(bus
		(pts
			(xy 113.665 130.81) (xy 114.935 130.81)
		)
		(stroke
			(width 0)
			(type default)
		)
	)
	(bus
		(pts
			(xy 116.205 194.31) (xy 116.205 196.85)
		)
		(stroke
			(width 0)
			(type default)
		)
	)
	(bus
		(pts
			(xy 116.205 199.39) (xy 116.205 201.93)
		)
		(stroke
			(width 0)
			(type default)
		)
	)
	(wire
		(pts
			(xy 139.7 165.1) (xy 191.77 165.1)
		)
		(stroke
			(width 0)
			(type default)
		)
	)
	(wire
		(pts
			(xy 159.385 182.88) (xy 191.77 182.88)
		)
		(stroke
			(width 0)
			(type default)
		)
	)
	(wire
		(pts
			(xy 139.7 99.06) (xy 191.77 99.06)
		)
		(stroke
			(width 0)
			(type default)
		)
	)
	(wire
		(pts
			(xy 189.865 177.8) (xy 191.77 177.8)
		)
		(stroke
			(width 0)
			(type default)
		)
	)
	(wire
		(pts
			(xy 139.7 139.7) (xy 191.77 139.7)
		)
		(stroke
			(width 0)
			(type default)
		)
	)
	(wire
		(pts
			(xy 139.7 111.76) (xy 191.77 111.76)
		)
		(stroke
			(width 0)
			(type default)
		)
	)
	(wire
		(pts
			(xy 117.475 134.62) (xy 191.77 134.62)
		)
		(stroke
			(width 0)
			(type default)
		)
	)
	(bus
		(pts
			(xy 138.43 135.89) (xy 138.43 138.43)
		)
		(stroke
			(width 0)
			(type default)
		)
	)
	(bus
		(pts
			(xy 138.43 138.43) (xy 138.43 140.97)
		)
		(stroke
			(width 0)
			(type default)
		)
	)
	(wire
		(pts
			(xy 117.475 193.04) (xy 191.77 193.04)
		)
		(stroke
			(width 0)
			(type default)
		)
	)
	(bus
		(pts
			(xy 116.205 191.77) (xy 116.205 194.31)
		)
		(stroke
			(width 0)
			(type default)
		)
	)
	(bus
		(pts
			(xy 138.43 107.95) (xy 138.43 110.49)
		)
		(stroke
			(width 0)
			(type default)
		)
	)
	(bus
		(pts
			(xy 138.43 120.65) (xy 138.43 128.27)
		)
		(stroke
			(width 0)
			(type default)
		)
	)
	(bus
		(pts
			(xy 116.205 168.91) (xy 116.205 186.69)
		)
		(stroke
			(width 0)
			(type default)
		)
	)
	(wire
		(pts
			(xy 139.7 142.24) (xy 191.77 142.24)
		)
		(stroke
			(width 0)
			(type default)
		)
	)
	(bus
		(pts
			(xy 138.43 128.27) (xy 138.43 130.81)
		)
		(stroke
			(width 0)
			(type default)
		)
	)
	(wire
		(pts
			(xy 117.475 200.66) (xy 191.77 200.66)
		)
		(stroke
			(width 0)
			(type default)
		)
	)
	(bus
		(pts
			(xy 138.43 130.81) (xy 138.43 135.89)
		)
		(stroke
			(width 0)
			(type default)
		)
	)
	(bus
		(pts
			(xy 116.205 189.23) (xy 116.205 191.77)
		)
		(stroke
			(width 0)
			(type default)
		)
	)
	(bus
		(pts
			(xy 138.43 163.83) (xy 138.43 212.09)
		)
		(stroke
			(width 0)
			(type default)
		)
	)
	(wire
		(pts
			(xy 117.475 187.96) (xy 191.77 187.96)
		)
		(stroke
			(width 0)
			(type default)
		)
	)
	(bus
		(pts
			(xy 116.205 158.75) (xy 116.205 166.37)
		)
		(stroke
			(width 0)
			(type default)
		)
	)
	(wire
		(pts
			(xy 117.475 208.28) (xy 191.77 208.28)
		)
		(stroke
			(width 0)
			(type default)
		)
	)
	(wire
		(pts
			(xy 139.7 213.36) (xy 191.77 213.36)
		)
		(stroke
			(width 0)
			(type default)
		)
	)
	(bus
		(pts
			(xy 138.43 146.05) (xy 138.43 148.59)
		)
		(stroke
			(width 0)
			(type default)
		)
	)
	(wire
		(pts
			(xy 159.385 180.34) (xy 191.77 180.34)
		)
		(stroke
			(width 0)
			(type default)
		)
	)
	(bus
		(pts
			(xy 116.205 133.35) (xy 116.205 158.75)
		)
		(stroke
			(width 0)
			(type default)
		)
	)
	(wire
		(pts
			(xy 139.7 106.68) (xy 191.77 106.68)
		)
		(stroke
			(width 0)
			(type default)
		)
	)
	(wire
		(pts
			(xy 117.475 160.02) (xy 191.77 160.02)
		)
		(stroke
			(width 0)
			(type default)
		)
	)
	(wire
		(pts
			(xy 117.475 195.58) (xy 191.77 195.58)
		)
		(stroke
			(width 0)
			(type default)
		)
	)
	(bus
		(pts
			(xy 135.89 95.885) (xy 137.795 95.885)
		)
		(stroke
			(width 0)
			(type default)
		)
	)
	(wire
		(pts
			(xy 189.865 175.26) (xy 191.77 175.26)
		)
		(stroke
			(width 0)
			(type default)
		)
	)
	(wire
		(pts
			(xy 117.475 170.18) (xy 191.77 170.18)
		)
		(stroke
			(width 0)
			(type default)
		)
	)
	(bus
		(pts
			(xy 138.43 140.97) (xy 138.43 146.05)
		)
		(stroke
			(width 0)
			(type default)
		)
	)
	(bus
		(pts
			(xy 138.43 153.67) (xy 138.43 163.83)
		)
		(stroke
			(width 0)
			(type default)
		)
	)
	(wire
		(pts
			(xy 189.865 83.82) (xy 191.77 83.82)
		)
		(stroke
			(width 0)
			(type default)
		)
	)
	(bus
		(pts
			(xy 158.115 179.07) (xy 158.115 181.61)
		)
		(stroke
			(width 0)
			(type default)
		)
	)
	(wire
		(pts
			(xy 139.7 109.22) (xy 191.77 109.22)
		)
		(stroke
			(width 0)
			(type default)
		)
	)
	(wire
		(pts
			(xy 189.865 210.82) (xy 191.77 210.82)
		)
		(stroke
			(width 0)
			(type default)
		)
	)
	(bus
		(pts
			(xy 116.205 196.85) (xy 116.205 199.39)
		)
		(stroke
			(width 0)
			(type default)
		)
	)
	(bus
		(pts
			(xy 155.575 176.53) (xy 157.48 176.53)
		)
		(stroke
			(width 0)
			(type default)
		)
	)
	(wire
		(pts
			(xy 139.7 149.86) (xy 191.77 149.86)
		)
		(stroke
			(width 0)
			(type default)
		)
	)
	(bus
		(pts
			(xy 114.935 130.81) (xy 116.205 132.08)
		)
		(stroke
			(width 0)
			(type default)
		)
	)
	(wire
		(pts
			(xy 117.475 167.64) (xy 191.77 167.64)
		)
		(stroke
			(width 0)
			(type default)
		)
	)
	(wire
		(pts
			(xy 117.475 205.74) (xy 191.77 205.74)
		)
		(stroke
			(width 0)
			(type default)
		)
	)
	(label "Control.PWR_GOOD"
		(at 159.385 182.88 0)
		(effects
			(font
				(size 1.27 1.27)
			)
			(justify left bottom)
		)
	)
	(label "ETH.TX_CTL"
		(at 139.7 106.68 0)
		(effects
			(font
				(size 1.27 1.27)
			)
			(justify left bottom)
		)
	)
	(label "ETH.MDC"
		(at 139.7 121.92 0)
		(effects
			(font
				(size 1.27 1.27)
			)
			(justify left bottom)
		)
	)
	(label "ETH.TXD2"
		(at 139.7 152.4 0)
		(effects
			(font
				(size 1.27 1.27)
			)
			(justify left bottom)
		)
	)
	(label "ETH.MDIO"
		(at 139.7 132.08 0)
		(effects
			(font
				(size 1.27 1.27)
			)
			(justify left bottom)
		)
	)
	(label "ETH.RXD2"
		(at 139.7 109.22 0)
		(effects
			(font
				(size 1.27 1.27)
			)
			(justify left bottom)
		)
	)
	(label "ETH.RXD0"
		(at 139.7 114.3 0)
		(effects
			(font
				(size 1.27 1.27)
			)
			(justify left bottom)
		)
	)
	(label "HyperRAM.DQ4"
		(at 117.475 200.66 0)
		(effects
			(font
				(size 1.27 1.27)
			)
			(justify left bottom)
		)
	)
	(label "HyperRAM.CK_N"
		(at 117.475 195.58 0)
		(effects
			(font
				(size 1.27 1.27)
			)
			(justify left bottom)
		)
	)
	(label "HyperRAM.RWDS"
		(at 117.475 167.64 0)
		(effects
			(font
				(size 1.27 1.27)
			)
			(justify left bottom)
		)
	)
	(label "ETH.RX_CTL"
		(at 139.7 137.16 0)
		(effects
			(font
				(size 1.27 1.27)
			)
			(justify left bottom)
		)
	)
	(label "HyperRAM.DQ6"
		(at 117.475 205.74 0)
		(effects
			(font
				(size 1.27 1.27)
			)
			(justify left bottom)
		)
	)
	(label "ETH.RXD1"
		(at 139.7 111.76 0)
		(effects
			(font
				(size 1.27 1.27)
			)
			(justify left bottom)
		)
	)
	(label "ETH.~{RESET}"
		(at 139.7 154.94 0)
		(effects
			(font
				(size 1.27 1.27)
			)
			(justify left bottom)
		)
	)
	(label "ETH.TXD3"
		(at 139.7 165.1 0)
		(effects
			(font
				(size 1.27 1.27)
			)
			(justify left bottom)
		)
	)
	(label "ETH.TXD1"
		(at 139.7 139.7 0)
		(effects
			(font
				(size 1.27 1.27)
			)
			(justify left bottom)
		)
	)
	(label "HyperRAM.DQ0"
		(at 117.475 198.12 0)
		(effects
			(font
				(size 1.27 1.27)
			)
			(justify left bottom)
		)
	)
	(label "ETH.REF_CLK"
		(at 139.7 142.24 0)
		(effects
			(font
				(size 1.27 1.27)
			)
			(justify left bottom)
		)
	)
	(label "HyperRAM.~{CS}"
		(at 117.475 134.62 0)
		(effects
			(font
				(size 1.27 1.27)
			)
			(justify left bottom)
		)
	)
	(label "ETH.TXC"
		(at 139.7 149.86 0)
		(effects
			(font
				(size 1.27 1.27)
			)
			(justify left bottom)
		)
	)
	(label "HyperRAM.CK_P"
		(at 117.475 193.04 0)
		(effects
			(font
				(size 1.27 1.27)
			)
			(justify left bottom)
		)
	)
	(label "HyperRAM.DQ3"
		(at 117.475 208.28 0)
		(effects
			(font
				(size 1.27 1.27)
			)
			(justify left bottom)
		)
	)
	(label "HyperRAM.~{RESET}"
		(at 117.475 160.02 0)
		(effects
			(font
				(size 1.27 1.27)
			)
			(justify left bottom)
		)
	)
	(label "HyperRAM.DQ7"
		(at 117.475 170.18 0)
		(effects
			(font
				(size 1.27 1.27)
			)
			(justify left bottom)
		)
	)
	(label "ETH.TXD0"
		(at 139.7 129.54 0)
		(effects
			(font
				(size 1.27 1.27)
			)
			(justify left bottom)
		)
	)
	(label "ETH.RXD3"
		(at 139.7 99.06 0)
		(effects
			(font
				(size 1.27 1.27)
			)
			(justify left bottom)
		)
	)
	(label "HyperRAM.DQ5"
		(at 117.475 190.5 0)
		(effects
			(font
				(size 1.27 1.27)
			)
			(justify left bottom)
		)
	)
	(label "HyperRAM.DQ2"
		(at 117.475 187.96 0)
		(effects
			(font
				(size 1.27 1.27)
			)
			(justify left bottom)
		)
	)
	(label "ETH.~{INT}"
		(at 139.7 213.36 0)
		(effects
			(font
				(size 1.27 1.27)
			)
			(justify left bottom)
		)
	)
	(label "ETH.RXC"
		(at 139.7 147.32 0)
		(effects
			(font
				(size 1.27 1.27)
			)
			(justify left bottom)
		)
	)
	(label "HyperRAM.DQ1"
		(at 117.475 203.2 0)
		(effects
			(font
				(size 1.27 1.27)
			)
			(justify left bottom)
		)
	)
	(label "Control.PWR_EN"
		(at 159.385 180.34 0)
		(effects
			(font
				(size 1.27 1.27)
			)
			(justify left bottom)
		)
	)
	(global_label "RFU_1"
		(shape input)
		(at 189.865 177.8 180)
		(fields_autoplaced yes)
		(effects
			(font
				(size 1.27 1.27)
			)
			(justify right)
		)
		(property "Intersheetrefs" "${INTERSHEET_REFS}"
			(at 181.6746 177.7206 0)
			(effects
				(font
					(size 1.27 1.27)
				)
				(justify right)
			)
		)
	)
	(global_label "RFU_3"
		(shape input)
		(at 189.865 172.72 180)
		(fields_autoplaced yes)
		(effects
			(font
				(size 1.27 1.27)
			)
			(justify right)
		)
		(property "Intersheetrefs" "${INTERSHEET_REFS}"
			(at 181.6746 172.6406 0)
			(effects
				(font
					(size 1.27 1.27)
				)
				(justify right)
			)
		)
	)
	(global_label "RFU_2"
		(shape input)
		(at 189.865 175.26 180)
		(fields_autoplaced yes)
		(effects
			(font
				(size 1.27 1.27)
			)
			(justify right)
		)
		(property "Intersheetrefs" "${INTERSHEET_REFS}"
			(at 181.6746 175.3394 0)
			(effects
				(font
					(size 1.27 1.27)
				)
				(justify right)
			)
		)
	)
	(global_label "TB_DETECT"
		(shape input)
		(at 189.865 185.42 180)
		(fields_autoplaced yes)
		(effects
			(font
				(size 1.27 1.27)
			)
			(justify right)
		)
		(property "Intersheetrefs" "${INTERSHEET_REFS}"
			(at 177.5622 185.4994 0)
			(effects
				(font
					(size 1.27 1.27)
				)
				(justify right)
			)
		)
	)
	(global_label "~{DDR_PRESENCE}"
		(shape input)
		(at 189.865 210.82 180)
		(fields_autoplaced yes)
		(effects
			(font
				(size 1.27 1.27)
			)
			(justify right)
		)
		(property "Intersheetrefs" "${INTERSHEET_REFS}"
			(at 172.966 210.8994 0)
			(effects
				(font
					(size 1.27 1.27)
				)
				(justify right)
			)
		)
	)
	(hierarchical_label "Control{DDR5}"
		(shape input)
		(at 155.575 176.53 180)
		(effects
			(font
				(size 1.27 1.27)
			)
			(justify right)
		)
	)
	(hierarchical_label "ETH{RGMII}"
		(shape bidirectional)
		(at 135.89 95.885 180)
		(effects
			(font
				(size 1.27 1.27)
			)
			(justify right)
		)
	)
	(hierarchical_label "HyperRAM{HyperBus}"
		(shape bidirectional)
		(at 113.665 130.81 180)
		(effects
			(font
				(size 1.27 1.27)
			)
			(justify right)
		)
	)
	(symbol
		(lib_id "antmicropower:+3V3")
		(at 189.865 81.915 0)
		(unit 1)
		(exclude_from_sim no)
		(in_bom yes)
		(on_board yes)
		(dnp no)
		(fields_autoplaced yes)
		(property "Reference" "#PWR0425"
			(at 189.865 85.725 0)
			(effects
				(font
					(size 1.27 1.27)
				)
				(hide yes)
			)
		)
		(property "Value" "+3V3"
			(at 186.69 79.375 0)
			(effects
				(font
					(size 1.27 1.27)
					(thickness 0.15)
				)
				(justify left bottom)
			)
		)
		(property "Footprint" ""
			(at 205.105 89.535 0)
			(effects
				(font
					(size 1.27 1.27)
					(thickness 0.15)
				)
				(justify left bottom)
				(hide yes)
			)
		)
		(property "Datasheet" ""
			(at 205.105 92.075 0)
			(effects
				(font
					(size 1.27 1.27)
					(thickness 0.15)
				)
				(justify left bottom)
				(hide yes)
			)
		)
		(property "Description" ""
			(at 189.865 81.915 0)
			(effects
				(font
					(size 1.27 1.27)
				)
			)
		)
		(property "Author" "Antmicro"
			(at 205.105 84.455 0)
			(effects
				(font
					(size 1.27 1.27)
					(thickness 0.15)
				)
				(justify left bottom)
				(hide yes)
			)
		)
		(property "License" "Apache-2.0"
			(at 205.105 86.995 0)
			(effects
				(font
					(size 1.27 1.27)
					(thickness 0.15)
				)
				(justify left bottom)
				(hide yes)
			)
		)
		(pin "1"
		)
		(instances
			(project "sodimm-ddr5-tester"
				(path ""
					(reference "#PWR0425")
					(unit 1)
				)
			)
		)
	)
	(symbol
		(lib_id "antmicroFPGAChips:XC7K160T-FFG676")
		(at 191.77 83.82 0)
		(unit 1)
		(exclude_from_sim no)
		(in_bom yes)
		(on_board yes)
		(dnp no)
		(fields_autoplaced yes)
		(property "Reference" "U4"
			(at 225.552 147.7594 0)
			(effects
				(font
					(size 1.27 1.27)
				)
				(justify left)
			)
		)
		(property "Value" "XC7K160T-FFG676"
			(at 225.552 150.2897 0)
			(effects
				(font
					(size 1.27 1.27)
					(thickness 0.15)
				)
				(justify left)
			)
		)
		(property "Footprint" "antmicro-footprints:BGA-676_27x27mm_Layout26x26_P1x1mm_FFG676"
			(at 260.35 86.36 0)
			(effects
				(font
					(size 1.27 1.27)
					(thickness 0.15)
				)
				(justify left bottom)
				(hide yes)
			)
		)
		(property "Datasheet" "https://docs.xilinx.com/v/u/en-US/ds180_7Series_Overview"
			(at 260.35 88.9 0)
			(effects
				(font
					(size 1.27 1.27)
					(thickness 0.15)
				)
				(justify left bottom)
				(hide yes)
			)
		)
		(property "Description" ""
			(at 191.77 83.82 0)
			(effects
				(font
					(size 1.27 1.27)
				)
			)
		)
		(property "MPN" "XC7K160T-FFG676"
			(at 191.77 83.82 0)
			(effects
				(font
					(size 1.27 1.27)
				)
				(hide yes)
			)
		)
		(property "Author" "Antmicro"
			(at 260.35 91.44 0)
			(effects
				(font
					(size 1.27 1.27)
					(thickness 0.15)
				)
				(justify left bottom)
				(hide yes)
			)
		)
		(property "License" "Apache-2.0"
			(at 260.35 93.98 0)
			(effects
				(font
					(size 1.27 1.27)
					(thickness 0.15)
				)
				(justify left bottom)
				(hide yes)
			)
		)
		(property "Manufacturer" "AMD-Xilinx"
			(at 191.77 83.82 0)
			(effects
				(font
					(size 1.27 1.27)
				)
				(hide yes)
			)
		)
		(pin "AA21"
		)
		(pin "AA22"
		)
		(pin "AA23"
		)
		(pin "AA24"
		)
		(pin "AA25"
		)
		(pin "AB21"
		)
		(pin "AB22"
		)
		(pin "AB24"
		)
		(pin "AB25"
		)
		(pin "AB26"
		)
		(pin "AC21"
		)
		(pin "AC22"
		)
		(pin "AC23"
		)
		(pin "AC24"
		)
		(pin "AC25"
		)
		(pin "AC26"
		)
		(pin "AD21"
		)
		(pin "AD22"
		)
		(pin "AD23"
		)
		(pin "AD24"
		)
		(pin "AD25"
		)
		(pin "AD26"
		)
		(pin "AE21"
		)
		(pin "AE22"
		)
		(pin "AE23"
		)
		(pin "AE25"
		)
		(pin "AE26"
		)
		(pin "AF22"
		)
		(pin "AF23"
		)
		(pin "AF24"
		)
		(pin "AF25"
		)
		(pin "AF26"
		)
		(pin "U21"
		)
		(pin "U22"
		)
		(pin "U23"
		)
		(pin "U24"
		)
		(pin "U25"
		)
		(pin "U26"
		)
		(pin "V20"
		)
		(pin "V21"
		)
		(pin "V22"
		)
		(pin "V23"
		)
		(pin "V24"
		)
		(pin "V26"
		)
		(pin "W20"
		)
		(pin "W21"
		)
		(pin "W23"
		)
		(pin "W24"
		)
		(pin "W25"
		)
		(pin "W26"
		)
		(pin "Y20"
		)
		(pin "Y21"
		)
		(pin "Y22"
		)
		(pin "Y23"
		)
		(pin "Y24"
		)
		(pin "Y25"
		)
		(pin "Y26"
		)
		(pin "K24"
		)
		(pin "K25"
		)
		(pin "K26"
		)
		(pin "L24"
		)
		(pin "L25"
		)
		(pin "M19"
		)
		(pin "M20"
		)
		(pin "M21"
		)
		(pin "M22"
		)
		(pin "M24"
		)
		(pin "M25"
		)
		(pin "M26"
		)
		(pin "N16"
		)
		(pin "N17"
		)
		(pin "N18"
		)
		(pin "N19"
		)
		(pin "N21"
		)
		(pin "N22"
		)
		(pin "N23"
		)
		(pin "N24"
		)
		(pin "N25"
		)
		(pin "N26"
		)
		(pin "P16"
		)
		(pin "P18"
		)
		(pin "P19"
		)
		(pin "P20"
		)
		(pin "P21"
		)
		(pin "P22"
		)
		(pin "P23"
		)
		(pin "P24"
		)
		(pin "P25"
		)
		(pin "P26"
		)
		(pin "R16"
		)
		(pin "R17"
		)
		(pin "R18"
		)
		(pin "R19"
		)
		(pin "R20"
		)
		(pin "R21"
		)
		(pin "R22"
		)
		(pin "R23"
		)
		(pin "R25"
		)
		(pin "R26"
		)
		(pin "T16"
		)
		(pin "T17"
		)
		(pin "T18"
		)
		(pin "T19"
		)
		(pin "T20"
		)
		(pin "T22"
		)
		(pin "T23"
		)
		(pin "T24"
		)
		(pin "T25"
		)
		(pin "T26"
		)
		(pin "U16"
		)
		(pin "U17"
		)
		(pin "U19"
		)
		(pin "U20"
		)
		(pin "A20"
		)
		(pin "A21"
		)
		(pin "A22"
		)
		(pin "A23"
		)
		(pin "A24"
		)
		(pin "A25"
		)
		(pin "B20"
		)
		(pin "B21"
		)
		(pin "B22"
		)
		(pin "B24"
		)
		(pin "B25"
		)
		(pin "B26"
		)
		(pin "C21"
		)
		(pin "C22"
		)
		(pin "C23"
		)
		(pin "C24"
		)
		(pin "C25"
		)
		(pin "C26"
		)
		(pin "D21"
		)
		(pin "D22"
		)
		(pin "D23"
		)
		(pin "D24"
		)
		(pin "D25"
		)
		(pin "D26"
		)
		(pin "E21"
		)
		(pin "E22"
		)
		(pin "E23"
		)
		(pin "E25"
		)
		(pin "E26"
		)
		(pin "F22"
		)
		(pin "F23"
		)
		(pin "F24"
		)
		(pin "F25"
		)
		(pin "F26"
		)
		(pin "G21"
		)
		(pin "G22"
		)
		(pin "G23"
		)
		(pin "G24"
		)
		(pin "G25"
		)
		(pin "G26"
		)
		(pin "H21"
		)
		(pin "H22"
		)
		(pin "H23"
		)
		(pin "H24"
		)
		(pin "H26"
		)
		(pin "J21"
		)
		(pin "J23"
		)
		(pin "J24"
		)
		(pin "J25"
		)
		(pin "J26"
		)
		(pin "K21"
		)
		(pin "K22"
		)
		(pin "K23"
		)
		(pin "L21"
		)
		(pin "L22"
		)
		(pin "L23"
		)
		(pin "A17"
		)
		(pin "A18"
		)
		(pin "A19"
		)
		(pin "B16"
		)
		(pin "B17"
		)
		(pin "B18"
		)
		(pin "B19"
		)
		(pin "C16"
		)
		(pin "C17"
		)
		(pin "C18"
		)
		(pin "C19"
		)
		(pin "D15"
		)
		(pin "D16"
		)
		(pin "D18"
		)
		(pin "D19"
		)
		(pin "D20"
		)
		(pin "E15"
		)
		(pin "E16"
		)
		(pin "E17"
		)
		(pin "E18"
		)
		(pin "E19"
		)
		(pin "E20"
		)
		(pin "F15"
		)
		(pin "F16"
		)
		(pin "F17"
		)
		(pin "F18"
		)
		(pin "F19"
		)
		(pin "F20"
		)
		(pin "G15"
		)
		(pin "G16"
		)
		(pin "G17"
		)
		(pin "G19"
		)
		(pin "G20"
		)
		(pin "H16"
		)
		(pin "H17"
		)
		(pin "H18"
		)
		(pin "H19"
		)
		(pin "H20"
		)
		(pin "J15"
		)
		(pin "J16"
		)
		(pin "J17"
		)
		(pin "J18"
		)
		(pin "J19"
		)
		(pin "J20"
		)
		(pin "K15"
		)
		(pin "K16"
		)
		(pin "K17"
		)
		(pin "K18"
		)
		(pin "K20"
		)
		(pin "L17"
		)
		(pin "L18"
		)
		(pin "L19"
		)
		(pin "L20"
		)
		(pin "M16"
		)
		(pin "M17"
		)
		(pin "M18"
		)
		(pin "A10"
		)
		(pin "A11"
		)
		(pin "A12"
		)
		(pin "A13"
		)
		(pin "A14"
		)
		(pin "A15"
		)
		(pin "A8"
		)
		(pin "A9"
		)
		(pin "B10"
		)
		(pin "B11"
		)
		(pin "B12"
		)
		(pin "B14"
		)
		(pin "B15"
		)
		(pin "B8"
		)
		(pin "B9"
		)
		(pin "C11"
		)
		(pin "C12"
		)
		(pin "C13"
		)
		(pin "C14"
		)
		(pin "C15"
		)
		(pin "C9"
		)
		(pin "D10"
		)
		(pin "D11"
		)
		(pin "D12"
		)
		(pin "D13"
		)
		(pin "D14"
		)
		(pin "D8"
		)
		(pin "D9"
		)
		(pin "E10"
		)
		(pin "E11"
		)
		(pin "E12"
		)
		(pin "E13"
		)
		(pin "E9"
		)
		(pin "F10"
		)
		(pin "F12"
		)
		(pin "F13"
		)
		(pin "F14"
		)
		(pin "F8"
		)
		(pin "F9"
		)
		(pin "G10"
		)
		(pin "G11"
		)
		(pin "G12"
		)
		(pin "G13"
		)
		(pin "G14"
		)
		(pin "G9"
		)
		(pin "H10"
		)
		(pin "H11"
		)
		(pin "H12"
		)
		(pin "H13"
		)
		(pin "H14"
		)
		(pin "H8"
		)
		(pin "H9"
		)
		(pin "J10"
		)
		(pin "J11"
		)
		(pin "J13"
		)
		(pin "J14"
		)
		(pin "J8"
		)
		(pin "AA14"
		)
		(pin "AA15"
		)
		(pin "AA17"
		)
		(pin "AA18"
		)
		(pin "AA19"
		)
		(pin "AA20"
		)
		(pin "AB14"
		)
		(pin "AB15"
		)
		(pin "AB16"
		)
		(pin "AB17"
		)
		(pin "AB18"
		)
		(pin "AB19"
		)
		(pin "AB20"
		)
		(pin "AC14"
		)
		(pin "AC15"
		)
		(pin "AC16"
		)
		(pin "AC17"
		)
		(pin "AC18"
		)
		(pin "AC19"
		)
		(pin "AD14"
		)
		(pin "AD15"
		)
		(pin "AD16"
		)
		(pin "AD18"
		)
		(pin "AD19"
		)
		(pin "AD20"
		)
		(pin "AE15"
		)
		(pin "AE16"
		)
		(pin "AE17"
		)
		(pin "AE18"
		)
		(pin "AE19"
		)
		(pin "AE20"
		)
		(pin "AF14"
		)
		(pin "AF15"
		)
		(pin "AF16"
		)
		(pin "AF17"
		)
		(pin "AF18"
		)
		(pin "AF19"
		)
		(pin "AF20"
		)
		(pin "V13"
		)
		(pin "V14"
		)
		(pin "V16"
		)
		(pin "V17"
		)
		(pin "V18"
		)
		(pin "V19"
		)
		(pin "W13"
		)
		(pin "W14"
		)
		(pin "W15"
		)
		(pin "W16"
		)
		(pin "W17"
		)
		(pin "W18"
		)
		(pin "W19"
		)
		(pin "Y14"
		)
		(pin "Y15"
		)
		(pin "Y16"
		)
		(pin "Y17"
		)
		(pin "Y18"
		)
		(pin "AA10"
		)
		(pin "AA11"
		)
		(pin "AA12"
		)
		(pin "AA13"
		)
		(pin "AA7"
		)
		(pin "AA8"
		)
		(pin "AA9"
		)
		(pin "AB10"
		)
		(pin "AB11"
		)
		(pin "AB12"
		)
		(pin "AB7"
		)
		(pin "AB8"
		)
		(pin "AB9"
		)
		(pin "AC11"
		)
		(pin "AC12"
		)
		(pin "AC13"
		)
		(pin "AC7"
		)
		(pin "AC8"
		)
		(pin "AC9"
		)
		(pin "AD10"
		)
		(pin "AD11"
		)
		(pin "AD12"
		)
		(pin "AD13"
		)
		(pin "AD8"
		)
		(pin "AD9"
		)
		(pin "AE10"
		)
		(pin "AE11"
		)
		(pin "AE12"
		)
		(pin "AE13"
		)
		(pin "AE7"
		)
		(pin "AE8"
		)
		(pin "AE9"
		)
		(pin "AF10"
		)
		(pin "AF12"
		)
		(pin "AF13"
		)
		(pin "AF7"
		)
		(pin "AF8"
		)
		(pin "AF9"
		)
		(pin "U9"
		)
		(pin "V10"
		)
		(pin "V11"
		)
		(pin "V12"
		)
		(pin "V7"
		)
		(pin "V8"
		)
		(pin "V9"
		)
		(pin "W10"
		)
		(pin "W11"
		)
		(pin "W7"
		)
		(pin "W8"
		)
		(pin "W9"
		)
		(pin "Y10"
		)
		(pin "Y11"
		)
		(pin "Y12"
		)
		(pin "Y13"
		)
		(pin "Y7"
		)
		(pin "Y8"
		)
		(pin "AA1"
		)
		(pin "AA2"
		)
		(pin "AA3"
		)
		(pin "AA4"
		)
		(pin "AA5"
		)
		(pin "AB1"
		)
		(pin "AB2"
		)
		(pin "AB4"
		)
		(pin "AB5"
		)
		(pin "AB6"
		)
		(pin "AC1"
		)
		(pin "AC2"
		)
		(pin "AC3"
		)
		(pin "AC4"
		)
		(pin "AC5"
		)
		(pin "AC6"
		)
		(pin "AD1"
		)
		(pin "AD2"
		)
		(pin "AD3"
		)
		(pin "AD4"
		)
		(pin "AD5"
		)
		(pin "AD6"
		)
		(pin "AE1"
		)
		(pin "AE2"
		)
		(pin "AE3"
		)
		(pin "AE5"
		)
		(pin "AE6"
		)
		(pin "AF2"
		)
		(pin "AF3"
		)
		(pin "AF4"
		)
		(pin "AF5"
		)
		(pin "AF6"
		)
		(pin "T7"
		)
		(pin "U1"
		)
		(pin "U2"
		)
		(pin "U3"
		)
		(pin "U4"
		)
		(pin "U5"
		)
		(pin "U6"
		)
		(pin "U7"
		)
		(pin "V1"
		)
		(pin "V2"
		)
		(pin "V3"
		)
		(pin "V4"
		)
		(pin "V6"
		)
		(pin "W1"
		)
		(pin "W3"
		)
		(pin "W4"
		)
		(pin "W5"
		)
		(pin "W6"
		)
		(pin "Y1"
		)
		(pin "Y2"
		)
		(pin "Y3"
		)
		(pin "Y4"
		)
		(pin "Y5"
		)
		(pin "Y6"
		)
		(pin "A3"
		)
		(pin "A4"
		)
		(pin "B1"
		)
		(pin "B2"
		)
		(pin "B5"
		)
		(pin "B6"
		)
		(pin "C3"
		)
		(pin "C4"
		)
		(pin "D1"
		)
		(pin "D2"
		)
		(pin "D5"
		)
		(pin "D6"
		)
		(pin "E3"
		)
		(pin "E4"
		)
		(pin "F1"
		)
		(pin "F2"
		)
		(pin "F5"
		)
		(pin "F6"
		)
		(pin "G3"
		)
		(pin "G4"
		)
		(pin "H1"
		)
		(pin "H2"
		)
		(pin "H5"
		)
		(pin "H6"
		)
		(pin "J3"
		)
		(pin "J4"
		)
		(pin "K1"
		)
		(pin "K2"
		)
		(pin "K5"
		)
		(pin "K6"
		)
		(pin "L3"
		)
		(pin "L4"
		)
		(pin "M1"
		)
		(pin "M2"
		)
		(pin "N3"
		)
		(pin "N4"
		)
		(pin "P1"
		)
		(pin "P2"
		)
		(pin "R3"
		)
		(pin "R4"
		)
		(pin "A1"
		)
		(pin "A16"
		)
		(pin "A2"
		)
		(pin "A26"
		)
		(pin "A5"
		)
		(pin "A6"
		)
		(pin "A7"
		)
		(pin "AA16"
		)
		(pin "AA26"
		)
		(pin "AA6"
		)
		(pin "AB13"
		)
		(pin "AB23"
		)
		(pin "AB3"
		)
		(pin "AC10"
		)
		(pin "AC20"
		)
		(pin "AD17"
		)
		(pin "AD7"
		)
		(pin "AE14"
		)
		(pin "AE24"
		)
		(pin "AE4"
		)
		(pin "AF1"
		)
		(pin "AF11"
		)
		(pin "AF21"
		)
		(pin "B13"
		)
		(pin "B23"
		)
		(pin "B3"
		)
		(pin "B4"
		)
		(pin "B7"
		)
		(pin "C1"
		)
		(pin "C10"
		)
		(pin "C2"
		)
		(pin "C20"
		)
		(pin "C5"
		)
		(pin "C6"
		)
		(pin "C7"
		)
		(pin "D17"
		)
		(pin "D3"
		)
		(pin "D4"
		)
		(pin "D7"
		)
		(pin "E1"
		)
		(pin "E14"
		)
		(pin "E2"
		)
		(pin "E24"
		)
		(pin "E5"
		)
		(pin "E6"
		)
		(pin "E7"
		)
		(pin "E8"
		)
		(pin "F11"
		)
		(pin "F21"
		)
		(pin "F3"
		)
		(pin "F4"
		)
		(pin "F7"
		)
		(pin "G1"
		)
		(pin "G18"
		)
		(pin "G2"
		)
		(pin "G5"
		)
		(pin "G6"
		)
		(pin "G8"
		)
		(pin "H15"
		)
		(pin "H25"
		)
		(pin "H3"
		)
		(pin "H4"
		)
		(pin "H7"
		)
		(pin "J1"
		)
		(pin "J12"
		)
		(pin "J2"
		)
		(pin "J22"
		)
		(pin "J5"
		)
		(pin "J6"
		)
		(pin "J9"
		)
		(pin "K10"
		)
		(pin "K11"
		)
		(pin "K12"
		)
		(pin "K13"
		)
		(pin "K14"
		)
		(pin "K19"
		)
		(pin "K3"
		)
		(pin "K4"
		)
		(pin "K7"
		)
		(pin "K8"
		)
		(pin "K9"
		)
		(pin "L1"
		)
		(pin "L10"
		)
		(pin "L11"
		)
		(pin "L12"
		)
		(pin "L13"
		)
		(pin "L14"
		)
		(pin "L15"
		)
		(pin "L16"
		)
		(pin "L2"
		)
		(pin "L26"
		)
		(pin "L5"
		)
		(pin "L6"
		)
		(pin "L9"
		)
		(pin "M10"
		)
		(pin "M11"
		)
		(pin "M12"
		)
		(pin "M13"
		)
		(pin "M14"
		)
		(pin "M15"
		)
		(pin "M23"
		)
		(pin "M3"
		)
		(pin "M4"
		)
		(pin "M5"
		)
		(pin "M6"
		)
		(pin "M7"
		)
		(pin "M8"
		)
		(pin "M9"
		)
		(pin "N1"
		)
		(pin "N10"
		)
		(pin "N13"
		)
		(pin "N14"
		)
		(pin "N15"
		)
		(pin "N2"
		)
		(pin "N20"
		)
		(pin "N5"
		)
		(pin "N6"
		)
		(pin "N7"
		)
		(pin "N9"
		)
		(pin "P10"
		)
		(pin "P13"
		)
		(pin "P14"
		)
		(pin "P15"
		)
		(pin "P17"
		)
		(pin "P3"
		)
		(pin "P4"
		)
		(pin "P8"
		)
		(pin "P9"
		)
		(pin "R1"
		)
		(pin "R10"
		)
		(pin "R13"
		)
		(pin "R14"
		)
		(pin "R15"
		)
		(pin "R2"
		)
		(pin "R24"
		)
		(pin "R5"
		)
		(pin "R8"
		)
		(pin "R9"
		)
		(pin "T1"
		)
		(pin "T10"
		)
		(pin "T11"
		)
		(pin "T12"
		)
		(pin "T13"
		)
		(pin "T14"
		)
		(pin "T15"
		)
		(pin "T21"
		)
		(pin "T3"
		)
		(pin "T4"
		)
		(pin "T8"
		)
		(pin "T9"
		)
		(pin "U10"
		)
		(pin "U11"
		)
		(pin "U12"
		)
		(pin "U13"
		)
		(pin "U14"
		)
		(pin "U15"
		)
		(pin "U18"
		)
		(pin "U8"
		)
		(pin "V15"
		)
		(pin "V25"
		)
		(pin "V5"
		)
		(pin "W12"
		)
		(pin "W2"
		)
		(pin "W22"
		)
		(pin "Y19"
		)
		(pin "Y9"
		)
		(pin "C8"
		)
		(pin "G7"
		)
		(pin "J7"
		)
		(pin "L7"
		)
		(pin "L8"
		)
		(pin "N11"
		)
		(pin "N12"
		)
		(pin "N8"
		)
		(pin "P11"
		)
		(pin "P12"
		)
		(pin "P5"
		)
		(pin "P6"
		)
		(pin "P7"
		)
		(pin "R11"
		)
		(pin "R12"
		)
		(pin "R6"
		)
		(pin "R7"
		)
		(pin "T2"
		)
		(pin "T5"
		)
		(pin "T6"
		)
		(instances
			(project "sodimm-ddr5-tester"
				(path ""
					(reference "U4")
					(unit 1)
				)
			)
		)
	)
)
